# SCM (Grand Teton) — schematic netlist excerpt (pin names and nets, part order shuffled) for the footprints in the layout excerpt that follows; sources: Cadence DE-HDL packaged netlist, KiCad conversion of 12092022_DA0F0TMDCD0_F0T_Management_Board_D_brd_V3_OCP.brd

R34  Q_RES  4.7K 1% EMPTY  pkg 0402LF  page 11 : A = P3V3_RGM ; B = RST_PLTRST_N
R717  Q_RES  4.7K 1% CHIP  pkg 0402LF  page 15 : A = P3V3_AUX ; B = RST_BMC_RSTBTN_OUT_N

(kicad_pcb
	(version 20260206)
	(generator "pcbnew")
	(generator_version "10.0")
	(general
		(thickness 1.6)
		(legacy_teardrops no)
	)
	(paper "A4")
	(title_block
		(title "12092022_DA0F0TMDCD0_F0T_Management_Board_D_brd_V3_OCP.brd")
		(comment 1 "Grand Teton / footprints 964-965 of 1440")
	)
	(layers
		(0 "F.Cu" signal "TOP")
		(4 "In1.Cu" signal "GND")
		(6 "In2.Cu" signal "IN1")
		(8 "In3.Cu" signal "GND1")
		(10 "In4.Cu" signal "IN2")
		(12 "In5.Cu" signal "VCC")
		(14 "In6.Cu" signal "VCC1")
		(16 "In7.Cu" signal "IN3")
		(18 "In8.Cu" signal "GND2")
		(20 "In9.Cu" signal "IN4")
		(22 "In10.Cu" signal "GND3")
		(2 "B.Cu" signal "BOTTOM")
		(9 "F.Adhes" user "F.Adhesive")
		(11 "B.Adhes" user "B.Adhesive")
		(13 "F.Paste" user "Package Geometry/Pastemask Top")
		(15 "B.Paste" user "Package Geometry/Pastemask Bottom")
		(5 "F.SilkS" user "Ref Des/Silkscreen Top")
		(7 "B.SilkS" user "Ref Des/Silkscreen Bottom")
		(1 "F.Mask" user "Board Geometry/Soldermask Top")
		(3 "B.Mask" user "Board Geometry/Soldermask Bottom")
		(17 "Dwgs.User" user "User.Drawings")
		(19 "Cmts.User" user "User.Comments")
		(21 "Eco1.User" user "User.Eco1")
		(23 "Eco2.User" user "User.Eco2")
		(25 "Edge.Cuts" user "Board Geometry/Outline")
		(27 "Margin" user)
		(31 "F.CrtYd" user "Package Geometry/Place Bound Top")
		(29 "B.CrtYd" user "Package Geometry/Place Bound Bottom")
		(35 "F.Fab" user "Ref Des/Assembly Top")
		(33 "B.Fab" user "Ref Des/Assembly Bottom")
	)
	(footprint ""
		(layer "B.Cu")
		(at 49.2252 -88.1126 -90)
		(property "Reference" "R34"
			(at 0 0 90)
			(layer "B.SilkS")
			(hide yes)
			(effects
				(font
					(size 1.27 1.27)
				)
				(justify mirror)
			)
		)
		(property "Value" ""
			(at 0 0 90)
			(layer "B.Fab")
			(effects
				(font
					(size 1.27 1.27)
				)
				(justify mirror)
			)
		)
		(duplicate_pad_numbers_are_jumpers no)
		(fp_line
			(start -0.7874 0.4064)
			(end 0.7874 0.4064)
			(stroke
				(width 0.1524)
				(type default)
			)
			(layer "B.SilkS")
		)
		(fp_line
			(start 0.7874 0.4064)
			(end 0.7874 -0.4064)
			(stroke
				(width 0.1524)
				(type default)
			)
			(layer "B.SilkS")
		)
		(fp_line
			(start -0.7874 -0.4064)
			(end -0.7874 0.4064)
			(stroke
				(width 0.1524)
				(type default)
			)
			(layer "B.SilkS")
		)
		(fp_line
			(start 0.7874 -0.4064)
			(end -0.7874 -0.4064)
			(stroke
				(width 0.1524)
				(type default)
			)
			(layer "B.SilkS")
		)
		(fp_line
			(start -0.67945 0.3048)
			(end -0.120396 0.3048)
			(stroke
				(width 0.1)
				(type default)
			)
			(layer "B.Fab")
		)
		(fp_line
			(start -0.120396 0.3048)
			(end -0.120396 0.2794)
			(stroke
				(width 0.1)
				(type default)
			)
			(layer "B.Fab")
		)
		(fp_line
			(start 0.12065 0.3048)
			(end 0.67945 0.3048)
			(stroke
				(width 0.1)
				(type default)
			)
			(layer "B.Fab")
		)
		(fp_line
			(start 0.67945 0.3048)
			(end 0.67945 -0.305054)
			(stroke
				(width 0.1)
				(type default)
			)
			(layer "B.Fab")
		)
		(fp_line
			(start -0.120396 0.2794)
			(end 0.12065 0.2794)
			(stroke
				(width 0.1)
				(type default)
			)
			(layer "B.Fab")
		)
		(fp_line
			(start 0.12065 0.2794)
			(end 0.12065 0.3048)
			(stroke
				(width 0.1)
				(type default)
			)
			(layer "B.Fab")
		)
		(fp_line
			(start -0.12065 -0.2794)
			(end -0.12065 -0.3048)
			(stroke
				(width 0.1)
				(type default)
			)
			(layer "B.Fab")
		)
		(fp_line
			(start 0.12065 -0.2794)
			(end -0.12065 -0.2794)
			(stroke
				(width 0.1)
				(type default)
			)
			(layer "B.Fab")
		)
		(fp_line
			(start -0.67945 -0.3048)
			(end -0.67945 0.3048)
			(stroke
				(width 0.1)
				(type default)
			)
			(layer "B.Fab")
		)
		(fp_line
			(start -0.12065 -0.3048)
			(end -0.67945 -0.3048)
			(stroke
				(width 0.1)
				(type default)
			)
			(layer "B.Fab")
		)
		(fp_line
			(start 0.12065 -0.305054)
			(end 0.12065 -0.2794)
			(stroke
				(width 0.1)
				(type default)
			)
			(layer "B.Fab")
		)
		(fp_line
			(start 0.67945 -0.305054)
			(end 0.12065 -0.305054)
			(stroke
				(width 0.1)
				(type default)
			)
			(layer "B.Fab")
		)
		(pad "1" smd circle
			(at 0.40005 0 90)
			(size 0 0)
			(layers "B.Cu" "B.Mask" "B.Paste")
			(net "P3V3_RGM")
		)
		(pad "2" smd circle
			(at -0.40005 0 90)
			(size 0 0)
			(layers "B.Cu" "B.Mask" "B.Paste")
			(net "RST_PLTRST_N")
		)
	)
	(footprint ""
		(layer "B.Cu")
		(at 39.80815 -59.0042)
		(property "Reference" "R717"
			(at 0 0 0)
			(layer "B.SilkS")
			(hide yes)
			(effects
				(font
					(size 1.27 1.27)
				)
				(justify mirror)
			)
		)
		(property "Value" ""
			(at 0 0 0)
			(layer "B.Fab")
			(effects
				(font
					(size 1.27 1.27)
				)
				(justify mirror)
			)
		)
		(duplicate_pad_numbers_are_jumpers no)
		(fp_line
			(start -0.7874 -0.4064)
			(end -0.7874 0.4064)
			(stroke
				(width 0.1524)
				(type default)
			)
			(layer "B.SilkS")
		)
		(fp_line
			(start -0.7874 0.4064)
			(end 0.7874 0.4064)
			(stroke
				(width 0.1524)
				(type default)
			)
			(layer "B.SilkS")
		)
		(fp_line
			(start 0.7874 -0.4064)
			(end -0.7874 -0.4064)
			(stroke
				(width 0.1524)
				(type default)
			)
			(layer "B.SilkS")
		)
		(fp_line
			(start 0.7874 0.4064)
			(end 0.7874 -0.4064)
			(stroke
				(width 0.1524)
				(type default)
			)
			(layer "B.SilkS")
		)
		(fp_line
			(start -0.67945 -0.3048)
			(end -0.67945 0.3048)
			(stroke
				(width 0.1)
				(type default)
			)
			(layer "B.Fab")
		)
		(fp_line
			(start -0.67945 0.3048)
			(end -0.120396 0.3048)
			(stroke
				(width 0.1)
				(type default)
			)
			(layer "B.Fab")
		)
		(fp_line
			(start -0.12065 -0.3048)
			(end -0.67945 -0.3048)
			(stroke
				(width 0.1)
				(type default)
			)
			(layer "B.Fab")
		)
		(fp_line
			(start -0.12065 -0.2794)
			(end -0.12065 -0.3048)
			(stroke
				(width 0.1)
				(type default)
			)
			(layer "B.Fab")
		)
		(fp_line
			(start -0.120396 0.2794)
			(end 0.12065 0.2794)
			(stroke
				(width 0.1)
				(type default)
			)
			(layer "B.Fab")
		)
		(fp_line
			(start -0.120396 0.3048)
			(end -0.120396 0.2794)
			(stroke
				(width 0.1)
				(type default)
			)
			(layer "B.Fab")
		)
		(fp_line
			(start 0.12065 -0.305054)
			(end 0.12065 -0.2794)
			(stroke
				(width 0.1)
				(type default)
			)
			(layer "B.Fab")
		)
		(fp_line
			(start 0.12065 -0.2794)
			(end -0.12065 -0.2794)
			(stroke
				(width 0.1)
				(type default)
			)
			(layer "B.Fab")
		)
		(fp_line
			(start 0.12065 0.2794)
			(end 0.12065 0.3048)
			(stroke
				(width 0.1)
				(type default)
			)
			(layer "B.Fab")
		)
		(fp_line
			(start 0.12065 0.3048)
			(end 0.67945 0.3048)
			(stroke
				(width 0.1)
				(type default)
			)
			(layer "B.Fab")
		)
		(fp_line
			(start 0.67945 -0.305054)
			(end 0.12065 -0.305054)
			(stroke
				(width 0.1)
				(type default)
			)
			(layer "B.Fab")
		)
		(fp_line
			(start 0.67945 0.3048)
			(end 0.67945 -0.305054)
			(stroke
				(width 0.1)
				(type default)
			)
			(layer "B.Fab")
		)
		(pad "1" smd circle
			(at 0.40005 0 180)
			(size 0 0)
			(layers "B.Cu" "B.Mask" "B.Paste")
			(net "P3V3_AUX")
		)
		(pad "2" smd circle
			(at -0.40005 0 180)
			(size 0 0)
			(layers "B.Cu" "B.Mask" "B.Paste")
			(net "RST_BMC_RSTBTN_OUT_N")
		)
	)
)
